# BASEBOARD_FAB2 (Tioga Pass) — schematic netlist excerpt (pin names and nets, part order shuffled) for the footprints in the layout excerpt that follows; sources: Cadence DE-HDL packaged netlist, KiCad conversion of Wiwynn_Tioga_Pass_MB.brd

C5U11  CAP_A  47UF 4V 20% X5R  pkg 0603V  page 217 : A = PVDDQ_ABC ; B = GND
C9P8  CAPP  470UF 2.5V 20% ALUM  pkg 3018  page 208 : A = PVCCIN_CPU1 ; B = GND
R2U21  RES  0.0 5% CHIP  pkg 0402  page 107 : A = P3E_CPU0_PE1_SS_RXN<3> ; B = P3E_CPU0_PE1_SS_R_RXN<3>

(kicad_pcb
	(version 20260206)
	(generator "pcbnew")
	(generator_version "10.0")
	(general
		(thickness 1.6)
		(legacy_teardrops no)
	)
	(paper "A4")
	(title_block
		(title "Wiwynn_Tioga_Pass_MB.brd")
		(comment 1 "Tioga Pass / footprints 2625-2627 of 4770")
	)
	(layers
		(0 "F.Cu" signal "TOP")
		(4 "In1.Cu" signal "L2GND")
		(6 "In2.Cu" signal "L3")
		(8 "In3.Cu" signal "L4GND")
		(10 "In4.Cu" signal "L5")
		(12 "In5.Cu" signal "L6GND")
		(14 "In6.Cu" signal "L7VCC")
		(16 "In7.Cu" signal "L8VCC")
		(18 "In8.Cu" signal "L9GND")
		(20 "In9.Cu" signal "L10")
		(22 "In10.Cu" signal "L11GND")
		(24 "In11.Cu" signal "L12")
		(26 "In12.Cu" signal "L13GND")
		(2 "B.Cu" signal "BOTTOM")
		(9 "F.Adhes" user "F.Adhesive")
		(11 "B.Adhes" user "B.Adhesive")
		(13 "F.Paste" user "Package Geometry/Pastemask Top")
		(15 "B.Paste" user "Package Geometry/Pastemask Bottom")
		(5 "F.SilkS" user "Ref Des/Silkscreen Top")
		(7 "B.SilkS" user "Ref Des/Silkscreen Bottom")
		(1 "F.Mask" user "Board Geometry/Soldermask Top")
		(3 "B.Mask" user "Board Geometry/Soldermask Bottom")
		(17 "Dwgs.User" user "User.Drawings")
		(19 "Cmts.User" user "User.Comments")
		(21 "Eco1.User" user "User.Eco1")
		(23 "Eco2.User" user "User.Eco2")
		(25 "Edge.Cuts" user "Board Geometry/Outline")
		(27 "Margin" user)
		(31 "F.CrtYd" user "Package Geometry/Place Bound Top")
		(29 "B.CrtYd" user "Package Geometry/Place Bound Bottom")
		(35 "F.Fab" user "Ref Des/Assembly Top")
		(33 "B.Fab" user "Ref Des/Assembly Bottom")
	)
	(footprint ""
		(layer "B.Cu")
		(at 45.212 -78.867 -90)
		(property "Reference" "C9P8"
			(at -0.60833 -3.429 0)
			(unlocked yes)
			(layer "B.SilkS")
			(effects
				(font
					(size 0.7874 0.5842)
					(thickness 0.1524)
				)
				(justify mirror)
			)
		)
		(property "Value" ""
			(at 0 0 90)
			(layer "B.Fab")
			(effects
				(font
					(size 1.27 1.27)
				)
				(justify mirror)
			)
		)
		(duplicate_pad_numbers_are_jumpers no)
		(fp_line
			(start -2.286 7.366)
			(end -1.600708 7.366)
			(stroke
				(width 0.1524)
				(type default)
			)
			(layer "B.SilkS")
		)
		(fp_line
			(start -2.286 7.366)
			(end -2.286 1.63195)
			(stroke
				(width 0.1524)
				(type default)
			)
			(layer "B.SilkS")
		)
		(fp_line
			(start 2.286 7.366)
			(end 1.60147 7.366)
			(stroke
				(width 0.1524)
				(type default)
			)
			(layer "B.SilkS")
		)
		(fp_line
			(start 2.286 7.366)
			(end 2.286 1.632712)
			(stroke
				(width 0.1524)
				(type default)
			)
			(layer "B.SilkS")
		)
		(fp_line
			(start -2.504948 1.633728)
			(end -1.6002 1.633728)
			(stroke
				(width 0.1524)
				(type default)
			)
			(layer "B.SilkS")
		)
		(fp_line
			(start 2.563114 1.633728)
			(end 1.6002 1.633728)
			(stroke
				(width 0.1524)
				(type default)
			)
			(layer "B.SilkS")
		)
		(fp_line
			(start -2.504948 -1.616456)
			(end -2.504948 1.633728)
			(stroke
				(width 0.1524)
				(type default)
			)
			(layer "B.SilkS")
		)
		(fp_line
			(start -1.6002 -1.616456)
			(end -2.504948 -1.616456)
			(stroke
				(width 0.1524)
				(type default)
			)
			(layer "B.SilkS")
		)
		(fp_line
			(start 1.6002 -1.616456)
			(end 2.563114 -1.616456)
			(stroke
				(width 0.1524)
				(type default)
			)
			(layer "B.SilkS")
		)
		(fp_line
			(start 2.563114 -1.616456)
			(end 2.563114 1.633728)
			(stroke
				(width 0.1524)
				(type default)
			)
			(layer "B.SilkS")
		)
		(fp_rect
			(start 2.286 7.366)
			(end -2.286 -0.254)
			(stroke
				(width 0)
				(type default)
			)
			(fill no)
			(layer "B.CrtYd")
		)
		(fp_line
			(start -2.286 7.366)
			(end 2.286 7.366)
			(stroke
				(width 0.1)
				(type default)
			)
			(layer "B.Fab")
		)
		(fp_line
			(start 2.286 7.366)
			(end 2.286 -0.254)
			(stroke
				(width 0.1)
				(type default)
			)
			(layer "B.Fab")
		)
		(fp_line
			(start -2.286 -0.254)
			(end -2.286 7.366)
			(stroke
				(width 0.1)
				(type default)
			)
			(layer "B.Fab")
		)
		(fp_line
			(start 2.286 -0.254)
			(end -2.286 -0.254)
			(stroke
				(width 0.1)
				(type default)
			)
			(layer "B.Fab")
		)
		(pad "1" smd rect
			(at 0 0 90)
			(size 2.54 3.048)
			(layers "B.Cu" "B.Mask" "B.Paste")
			(net "PVCCIN_CPU1")
		)
		(pad "2" smd rect
			(at 0 7.112 90)
			(size 2.54 3.048)
			(layers "B.Cu" "B.Mask" "B.Paste")
			(net "GND")
		)
	)
	(footprint ""
		(layer "B.Cu")
		(at 258.445 -8.0772 -90)
		(property "Reference" "C5U11"
			(at 0 0 90)
			(layer "B.SilkS")
			(hide yes)
			(effects
				(font
					(size 1.27 1.27)
				)
				(justify mirror)
			)
		)
		(property "Value" ""
			(at 0 0 90)
			(layer "B.Fab")
			(effects
				(font
					(size 1.27 1.27)
				)
				(justify mirror)
			)
		)
		(duplicate_pad_numbers_are_jumpers no)
		(fp_rect
			(start 0.500126 1.598422)
			(end -0.500126 -0.201422)
			(stroke
				(width 0)
				(type default)
			)
			(fill no)
			(layer "B.CrtYd")
		)
		(fp_line
			(start -0.500126 1.598422)
			(end 0.500126 1.598422)
			(stroke
				(width 0.1)
				(type default)
			)
			(layer "B.Fab")
		)
		(fp_line
			(start 0.500126 1.598422)
			(end 0.500126 -0.201422)
			(stroke
				(width 0.1)
				(type default)
			)
			(layer "B.Fab")
		)
		(fp_line
			(start -0.500126 -0.201422)
			(end -0.500126 1.598422)
			(stroke
				(width 0.1)
				(type default)
			)
			(layer "B.Fab")
		)
		(fp_line
			(start 0.500126 -0.201422)
			(end -0.500126 -0.201422)
			(stroke
				(width 0.1)
				(type default)
			)
			(layer "B.Fab")
		)
		(pad "1" smd rect
			(at 0 0 180)
			(size 0.889 0.9906)
			(layers "B.Cu" "B.Mask" "B.Paste")
			(net "PVDDQ_ABC")
		)
		(pad "2" smd rect
			(at 0 1.397 180)
			(size 0.889 0.9906)
			(layers "B.Cu" "B.Mask" "B.Paste")
			(net "GND")
		)
		(zone
			(layer "B.Cu")
			(hatch none 0.5)
			(connect_pads
				(clearance 0)
			)
			(min_thickness 0.25)
			(keepout
				(tracks allowed)
				(vias not_allowed)
				(pads allowed)
				(copperpour not_allowed)
				(footprints allowed)
			)
			(placement
				(enabled no)
				(sheetname "")
			)
			(fill
				(thermal_gap 0.5)
				(thermal_bridge_width 0.5)
				(island_removal_mode 0)
			)
			(polygon
				(pts
					(xy 257.4925 -7.5819) (xy 258.0005 -7.5819) (xy 258.0005 -8.5725) (xy 257.4925 -8.5725)
				)
			)
		)
		(zone
			(layer "B.Cu")
			(hatch none 0.5)
			(connect_pads
				(clearance 0)
			)
			(min_thickness 0.25)
			(keepout
				(tracks not_allowed)
				(vias allowed)
				(pads allowed)
				(copperpour not_allowed)
				(footprints allowed)
			)
			(placement
				(enabled no)
				(sheetname "")
			)
			(fill
				(thermal_gap 0.5)
				(thermal_bridge_width 0.5)
				(island_removal_mode 0)
			)
			(polygon
				(pts
					(xy 257.4925 -7.5819) (xy 258.0005 -7.5819) (xy 258.0005 -8.5725) (xy 257.4925 -8.5725)
				)
			)
		)
	)
	(footprint ""
		(layer "B.Cu")
		(at 343.125806 -60.368434)
		(property "Reference" "R2U21"
			(at 0 0 0)
			(layer "B.SilkS")
			(hide yes)
			(effects
				(font
					(size 1.27 1.27)
				)
				(justify mirror)
			)
		)
		(property "Value" ""
			(at 0 0 0)
			(layer "B.Fab")
			(effects
				(font
					(size 1.27 1.27)
				)
				(justify mirror)
			)
		)
		(duplicate_pad_numbers_are_jumpers no)
		(fp_poly
			(pts
				(xy 0.2794 -0.1016) (xy -0.2794 -0.1016) (xy -0.2794 0.9906) (xy 0.2794 0.9906)
			)
			(stroke
				(width 0)
				(type default)
			)
			(fill no)
			(layer "B.CrtYd")
		)
		(fp_line
			(start -0.2794 -0.1016)
			(end 0.2794 -0.1016)
			(stroke
				(width 0.1)
				(type default)
			)
			(layer "B.Fab")
		)
		(fp_line
			(start -0.2794 0.9906)
			(end -0.2794 -0.1016)
			(stroke
				(width 0.1)
				(type default)
			)
			(layer "B.Fab")
		)
		(fp_line
			(start 0.2794 -0.1016)
			(end 0.2794 0.9906)
			(stroke
				(width 0.1)
				(type default)
			)
			(layer "B.Fab")
		)
		(fp_line
			(start 0.2794 0.9906)
			(end -0.2794 0.9906)
			(stroke
				(width 0.1)
				(type default)
			)
			(layer "B.Fab")
		)
		(pad "1" smd rect
			(at 0 0 180)
			(size 0.508 0.508)
			(layers "B.Cu" "B.Mask" "B.Paste")
			(net "P3E_CPU0_PE1_SS_RXN<3>")
		)
		(pad "2" smd rect
			(at 0 0.889 180)
			(size 0.508 0.508)
			(layers "B.Cu" "B.Mask" "B.Paste")
			(net "P3E_CPU0_PE1_SS_R_RXN<3>")
		)
		(zone
			(layer "B.Cu")
			(hatch none 0.5)
			(connect_pads
				(clearance 0)
			)
			(min_thickness 0.25)
			(keepout
				(tracks allowed)
				(vias not_allowed)
				(pads allowed)
				(copperpour not_allowed)
				(footprints allowed)
			)
			(placement
				(enabled no)
				(sheetname "")
			)
			(fill
				(thermal_gap 0.5)
				(thermal_bridge_width 0.5)
				(island_removal_mode 0)
			)
			(polygon
				(pts
					(xy 343.379806 -60.114434) (xy 342.871806 -60.114434) (xy 342.871806 -59.733434) (xy 343.379806 -59.733434)
				)
			)
		)
		(zone
			(layer "B.Cu")
			(hatch none 0.5)
			(connect_pads
				(clearance 0)
			)
			(min_thickness 0.25)
			(keepout
				(tracks not_allowed)
				(vias allowed)
				(pads allowed)
				(copperpour not_allowed)
				(footprints allowed)
			)
			(placement
				(enabled no)
				(sheetname "")
			)
			(fill
				(thermal_gap 0.5)
				(thermal_bridge_width 0.5)
				(island_removal_mode 0)
			)
			(polygon
				(pts
					(xy 343.379806 -59.733434) (xy 342.871806 -59.733434) (xy 342.871806 -60.114434) (xy 343.379806 -60.114434)
				)
			)
		)
	)
)
